# Altium SchDoc records: 03-M2_GoldFingers.SchDoc
|HEADER=Protel for Windows - Schematic Capture Binary File Version 5.0|Weight=446|MinorVersion=9
|RECORD=31|FontIdCount=2|Size1=10|FontName1=Times New Roman|Size2=10|Rotation2=90|FontName2=Times New Roman|UseMBCS=T|IsBOC=T|HotSpotGridOn=T|HotSpotGridSize=4|SheetStyle=6|SystemFont=1|BorderOn=T|TitleBlockOn=T|SheetNumberSpaceSize=12|AreaColor=16317695|SnapGridOn=T|SnapGridSize=10|VisibleGridOn=T|VisibleGridSize=10|CustomX=1500|CustomY=950|CustomXZones=6|CustomYZones=4|CustomMarginWidth=20|Display_Unit=0
|RECORD=41|OwnerPartId=-1|Color=8388608|FontID=1|IsHidden=T|Text=*|Name=CurrentTime|ReadOnlyState=1
|RECORD=41|IndexInSheet=1|OwnerPartId=-1|Color=8388608|FontID=1|IsHidden=T|Text=*|Name=CurrentDate|ReadOnlyState=1
|RECORD=41|IndexInSheet=2|OwnerPartId=-1|Color=8388608|FontID=1|IsHidden=T|Text=*|Name=Time|ReadOnlyState=1
|RECORD=41|IndexInSheet=3|OwnerPartId=-1|Color=8388608|FontID=1|IsHidden=T|Text=*|Name=Date|ReadOnlyState=1
|RECORD=41|IndexInSheet=4|OwnerPartId=-1|Color=8388608|FontID=1|IsHidden=T|Text=*|Name=DocumentFullPathAndName|ReadOnlyState=1
|RECORD=41|IndexInSheet=5|OwnerPartId=-1|Color=8388608|FontID=1|IsHidden=T|Text=*|Name=DocumentName|ReadOnlyState=1
|RECORD=41|IndexInSheet=6|OwnerPartId=-1|Color=8388608|FontID=1|IsHidden=T|Text=*|Name=ModifiedDate|ReadOnlyState=1
|RECORD=41|IndexInSheet=7|OwnerPartId=-1|Color=8388608|FontID=1|IsHidden=T|Text=*|Name=ApprovedBy|ReadOnlyState=1
|RECORD=41|IndexInSheet=8|OwnerPartId=-1|Color=8388608|FontID=1|IsHidden=T|Text=*|Name=CheckedBy|ReadOnlyState=1
|RECORD=41|IndexInSheet=9|OwnerPartId=-1|Color=8388608|FontID=1|IsHidden=T|Text=*|Name=Author|ReadOnlyState=1
|RECORD=41|IndexInSheet=10|OwnerPartId=-1|Color=8388608|FontID=1|IsHidden=T|Text=*|Name=CompanyName|ReadOnlyState=1
|RECORD=41|IndexInSheet=11|OwnerPartId=-1|Color=8388608|FontID=1|IsHidden=T|Text=*|Name=DrawnBy|ReadOnlyState=1
|RECORD=41|IndexInSheet=12|OwnerPartId=-1|Color=8388608|FontID=1|IsHidden=T|Text=*|Name=Engineer|ReadOnlyState=1
|RECORD=41|IndexInSheet=13|OwnerPartId=-1|Color=8388608|FontID=1|IsHidden=T|Text=*|Name=Organization|ReadOnlyState=1
|RECORD=41|IndexInSheet=14|OwnerPartId=-1|Color=8388608|FontID=1|IsHidden=T|Text=*|Name=Address1|ReadOnlyState=1
|RECORD=41|IndexInSheet=15|OwnerPartId=-1|Color=8388608|FontID=1|IsHidden=T|Text=*|Name=Address2|ReadOnlyState=1
|RECORD=41|IndexInSheet=16|OwnerPartId=-1|Color=8388608|FontID=1|IsHidden=T|Text=*|Name=Address3|ReadOnlyState=1
|RECORD=41|IndexInSheet=17|OwnerPartId=-1|Color=8388608|FontID=1|IsHidden=T|Text=*|Name=Address4|ReadOnlyState=1
|RECORD=41|IndexInSheet=18|OwnerPartId=-1|Color=8388608|FontID=1|IsHidden=T|Text=*|Name=Title|ReadOnlyState=1
|RECORD=41|IndexInSheet=19|OwnerPartId=-1|Color=8388608|FontID=1|IsHidden=T|Text=*|Name=DocumentNumber|ReadOnlyState=1
|RECORD=41|IndexInSheet=20|OwnerPartId=-1|Color=8388608|FontID=1|IsHidden=T|Text=*|Name=Revision|ReadOnlyState=1
|RECORD=41|IndexInSheet=21|OwnerPartId=-1|Color=8388608|FontID=1|IsHidden=T|Text=3|Name=SheetNumber|ReadOnlyState=1
|RECORD=41|IndexInSheet=22|OwnerPartId=-1|Color=8388608|FontID=1|IsHidden=T|Text=3|Name=SheetTotal|ReadOnlyState=1
|RECORD=41|IndexInSheet=23|OwnerPartId=-1|Color=8388608|FontID=1|IsHidden=T|Text=*|Name=Rule|ReadOnlyState=1
|RECORD=41|IndexInSheet=24|OwnerPartId=-1|Color=8388608|FontID=1|IsHidden=T|Text=*|Name=ImagePath|ReadOnlyState=1
|RECORD=41|IndexInSheet=25|OwnerPartId=-1|Color=8388608|FontID=1|IsHidden=T|Text=*|Name=ProjectName|ReadOnlyState=1
|RECORD=41|IndexInSheet=26|OwnerPartId=-1|Color=8388608|FontID=1|IsHidden=T|Text=*|Name=Application_BuildNumber|ReadOnlyState=1
|RECORD=1|LibReference=OCPTAP_M2_FINGERS|PartCount=2|DisplayModeCount=1|IndexInSheet=27|OwnerPartId=-1|Location.X=680|Location.Y=630|CurrentPartId=1|LibraryPath=*|SourceLibraryName=M2_Library.SchLib|TargetFileName=*|AreaColor=11599871|Color=128|PartIDLocked=T|NotUseDBTableName=T|DesignItemId=OCPTAP_M2_FINGERS|AllPinCount=67|ComponentKindVersion2=5
|RECORD=14|OwnerIndex=28|IsNotAccesible=T|OwnerPartId=1|Location.X=710|Location.Y=250|Corner.X=860|Corner.Y=720|Color=128|AreaColor=11599871|IsSolid=T
|RECORD=2|OwnerIndex=28|OwnerPartId=1|FormalType=1|PinConglomerate=58|PinLength=30|Location.X=710|Location.Y=710|Name=V3P3_1|Designator=2|SwapIDPart=Ž&Ž||PinPropagationDelay=0.000000E+000
|RECORD=2|OwnerIndex=28|OwnerPartId=1|FormalType=1|PinConglomerate=58|PinLength=30|Location.X=710|Location.Y=700|Name=V3P3_2|Designator=4|SwapIDPart=Ž&Ž||PinPropagationDelay=0.000000E+000
|RECORD=2|OwnerIndex=28|OwnerPartId=1|FormalType=1|PinConglomerate=58|PinLength=30|Location.X=710|Location.Y=620|Name=SMCLK|Designator=40|SwapIDPart=Ž&Ž||PinPropagationDelay=0.000000E+000
|RECORD=2|OwnerIndex=28|OwnerPartId=1|FormalType=1|PinConglomerate=58|PinLength=30|Location.X=710|Location.Y=610|Name=SMDAT|Designator=42|SwapIDPart=Ž&Ž||PinPropagationDelay=0.000000E+000
|RECORD=2|OwnerIndex=28|OwnerPartId=1|FormalType=1|PinConglomerate=58|PinLength=30|Location.X=710|Location.Y=600|Name=ALERT_L|Designator=44|SwapIDPart=Ž&Ž||PinPropagationDelay=0.000000E+000
|RECORD=2|OwnerIndex=28|OwnerPartId=1|FormalType=1|PinConglomerate=58|PinLength=30|Location.X=710|Location.Y=640|Name=PERST_L|Designator=50|SwapIDPart=Ž&Ž||PinPropagationDelay=0.000000E+000
|RECORD=2|OwnerIndex=28|OwnerPartId=1|FormalType=1|PinConglomerate=56|PinLength=30|Location.X=860|Location.Y=390|Name=NC|Designator=52|SwapIDPart=Ž&Ž||PinPropagationDelay=0.000000E+000
|RECORD=2|OwnerIndex=28|OwnerPartId=1|FormalType=1|PinConglomerate=56|PinLength=30|Location.X=860|Location.Y=370|Name=NC|Designator=54|SwapIDPart=Ž&Ž||PinPropagationDelay=0.000000E+000
|RECORD=2|OwnerIndex=28|OwnerPartId=1|FormalType=1|PinConglomerate=56|PinLength=30|Location.X=860|Location.Y=630|Name=PPS_OUT_OPT|Designator=35|SwapIDPart=Ž&Ž||PinPropagationDelay=0.000000E+000
|RECORD=2|OwnerIndex=28|OwnerPartId=1|FormalType=1|PinConglomerate=58|PinLength=30|Location.X=710|Location.Y=430|Name=GND|Designator=3|SwapIDPart=Ž&Ž||PinPropagationDelay=0.000000E+000
|RECORD=2|OwnerIndex=28|OwnerPartId=1|FormalType=1|PinConglomerate=58|PinLength=30|Location.X=710|Location.Y=420|Name=GND|Designator=5|SwapIDPart=Ž&Ž||PinPropagationDelay=0.000000E+000
|RECORD=2|OwnerIndex=28|OwnerPartId=1|FormalType=1|PinConglomerate=58|PinLength=30|Location.X=710|Location.Y=410|Name=GND|Designator=11|SwapIDPart=Ž&Ž||PinPropagationDelay=0.000000E+000
|RECORD=2|OwnerIndex=28|OwnerPartId=1|FormalType=1|PinConglomerate=58|PinLength=30|Location.X=710|Location.Y=530|Name=CONFIG_0(GND)|Designator=21|SwapIDPart=Ž&Ž||PinPropagationDelay=0.000000E+000
|RECORD=2|OwnerIndex=28|OwnerPartId=1|FormalType=1|PinConglomerate=58|PinLength=30|Location.X=710|Location.Y=400|Name=GND|Designator=27|SwapIDPart=Ž&Ž||PinPropagationDelay=0.000000E+000
|RECORD=2|OwnerIndex=28|OwnerPartId=1|FormalType=1|PinConglomerate=58|PinLength=30|Location.X=710|Location.Y=390|Name=GND|Designator=33|SwapIDPart=Ž&Ž||PinPropagationDelay=0.000000E+000
|RECORD=2|OwnerIndex=28|OwnerPartId=1|FormalType=1|PinConglomerate=58|PinLength=30|Location.X=710|Location.Y=380|Name=GND|Designator=39|SwapIDPart=Ž&Ž||PinPropagationDelay=0.000000E+000
|RECORD=2|OwnerIndex=28|OwnerPartId=1|FormalType=1|PinConglomerate=58|PinLength=30|Location.X=710|Location.Y=370|Name=GND|Designator=45|SwapIDPart=Ž&Ž||PinPropagationDelay=0.000000E+000
|RECORD=2|OwnerIndex=28|OwnerPartId=1|FormalType=1|PinConglomerate=58|PinLength=30|Location.X=710|Location.Y=360|Name=GND|Designator=51|SwapIDPart=Ž&Ž||PinPropagationDelay=0.000000E+000
|RECORD=2|OwnerIndex=28|OwnerPartId=1|FormalType=1|PinConglomerate=58|PinLength=30|Location.X=710|Location.Y=350|Name=GND|Designator=57|SwapIDPart=Ž&Ž||PinPropagationDelay=0.000000E+000
|RECORD=2|OwnerIndex=28|OwnerPartId=1|FormalType=1|PinConglomerate=58|PinLength=30|Location.X=710|Location.Y=340|Name=GND|Designator=71|SwapIDPart=Ž&Ž||PinPropagationDelay=0.000000E+000
|RECORD=2|OwnerIndex=28|OwnerPartId=1|FormalType=1|PinConglomerate=58|PinLength=30|Location.X=710|Location.Y=490|Name=VIO_CFG(GND)|Designator=73|SwapIDPart=Ž&Ž||PinPropagationDelay=0.000000E+000
|RECORD=2|OwnerIndex=28|OwnerPartId=1|FormalType=1|PinConglomerate=58|PinLength=30|Location.X=710|Location.Y=510|Name=CONFIG_2(GND)|Designator=75|SwapIDPart=Ž&Ž||PinPropagationDelay=0.000000E+000
|RECORD=2|OwnerIndex=28|OwnerPartId=1|FormalType=1|PinConglomerate=58|PinLength=30|Location.X=710|Location.Y=670|Name=V3P3_7|Designator=70|SwapIDPart=Ž&Ž||PinPropagationDelay=0.000000E+000
|RECORD=2|OwnerIndex=28|OwnerPartId=1|FormalType=1|PinConglomerate=58|PinLength=30|Location.X=710|Location.Y=680|Name=V3P3_8|Designator=72|SwapIDPart=Ž&Ž||PinPropagationDelay=0.000000E+000
|RECORD=2|OwnerIndex=28|OwnerPartId=1|FormalType=1|PinConglomerate=58|PinLength=30|Location.X=710|Location.Y=690|Name=V3P3_9|Designator=74|SwapIDPart=Ž&Ž||PinPropagationDelay=0.000000E+000
|RECORD=2|OwnerIndex=28|OwnerPartId=1|FormalType=1|PinConglomerate=56|PinLength=30|Location.X=860|Location.Y=690|Name=LED1_L|Designator=10|SwapIDPart=Ž&Ž||PinPropagationDelay=0.000000E+000
|RECORD=2|OwnerIndex=28|OwnerPartId=1|FormalType=1|PinConglomerate=56|PinLength=30|Location.X=860|Location.Y=350|Name=NC|Designator=56|SwapIDPart=Ž&Ž||PinPropagationDelay=0.000000E+000
|RECORD=2|OwnerIndex=28|OwnerPartId=1|FormalType=1|PinConglomerate=56|PinLength=30|Location.X=860|Location.Y=340|Name=NC|Designator=58|SwapIDPart=Ž&Ž||PinPropagationDelay=0.000000E+000
|RECORD=2|OwnerIndex=28|OwnerPartId=1|FormalType=1|Electrical=2|PinConglomerate=56|PinLength=30|Location.X=860|Location.Y=600|Name=UARTIN_RX|Designator=62|SwapIDPart=Ž&Ž||PinPropagationDelay=0.000000E+000
|RECORD=2|OwnerIndex=28|OwnerPartId=1|FormalType=1|Electrical=2|PinConglomerate=56|PinLength=30|Location.X=860|Location.Y=710|Name=PWR_OFF|Designator=6|SwapIDPart=Ž&Ž||PinPropagationDelay=0.000000E+000
|RECORD=2|OwnerIndex=28|OwnerPartId=1|FormalType=1|Electrical=2|PinConglomerate=56|PinLength=30|Location.X=860|Location.Y=700|Name=W_DISABLE#|Designator=8|SwapIDPart=Ž&Ž||PinPropagationDelay=0.000000E+000
|RECORD=2|OwnerIndex=28|OwnerPartId=1|FormalType=1|Electrical=2|PinConglomerate=56|PinLength=30|Location.X=860|Location.Y=660|Name=10MHZ_IN|Designator=20|SwapIDPart=Ž&Ž||PinPropagationDelay=0.000000E+000
|RECORD=2|OwnerIndex=28|OwnerPartId=1|FormalType=1|Electrical=2|PinConglomerate=56|PinLength=30|Location.X=860|Location.Y=650|Name=PPS_IN|Designator=22|SwapIDPart=Ž&Ž||PinPropagationDelay=0.000000E+000
|RECORD=2|OwnerIndex=28|OwnerPartId=1|FormalType=1|PinConglomerate=56|PinLength=30|Location.X=860|Location.Y=550|Name=NC|Designator=24|SwapIDPart=Ž&Ž||PinPropagationDelay=0.000000E+000
|RECORD=2|OwnerIndex=28|OwnerPartId=1|FormalType=1|PinConglomerate=56|PinLength=30|Location.X=860|Location.Y=530|Name=NC|Designator=26|SwapIDPart=Ž&Ž||PinPropagationDelay=0.000000E+000
|RECORD=2|OwnerIndex=28|OwnerPartId=1|FormalType=1|PinConglomerate=56|PinLength=30|Location.X=860|Location.Y=520|Name=NC|Designator=28|SwapIDPart=Ž&Ž||PinPropagationDelay=0.000000E+000
|RECORD=2|OwnerIndex=28|OwnerPartId=1|FormalType=1|PinConglomerate=56|PinLength=30|Location.X=860|Location.Y=500|Name=NC|Designator=30|SwapIDPart=Ž&Ž||PinPropagationDelay=0.000000E+000
|RECORD=2|OwnerIndex=28|OwnerPartId=1|FormalType=1|PinConglomerate=56|PinLength=30|Location.X=860|Location.Y=480|Name=NC|Designator=32|SwapIDPart=Ž&Ž||PinPropagationDelay=0.000000E+000
|RECORD=2|OwnerIndex=28|OwnerPartId=1|FormalType=1|PinConglomerate=56|PinLength=30|Location.X=860|Location.Y=470|Name=NC|Designator=34|SwapIDPart=Ž&Ž||PinPropagationDelay=0.000000E+000
|RECORD=2|OwnerIndex=28|OwnerPartId=1|FormalType=1|PinConglomerate=56|PinLength=30|Location.X=860|Location.Y=460|Name=NC|Designator=36|SwapIDPart=Ž&Ž||PinPropagationDelay=0.000000E+000
|RECORD=2|OwnerIndex=28|OwnerPartId=1|FormalType=1|PinConglomerate=56|PinLength=30|Location.X=860|Location.Y=440|Name=NC|Designator=38|SwapIDPart=Ž&Ž||PinPropagationDelay=0.000000E+000
|RECORD=2|OwnerIndex=28|OwnerPartId=1|FormalType=1|PinConglomerate=56|PinLength=30|Location.X=860|Location.Y=620|Name=PPS_OUT|Designator=46|SwapIDPart=Ž&Ž||PinPropagationDelay=0.000000E+000
|RECORD=2|OwnerIndex=28|OwnerPartId=1|FormalType=1|PinConglomerate=56|PinLength=30|Location.X=860|Location.Y=640|Name=10MHZ_OUT|Designator=48|SwapIDPart=Ž&Ž||PinPropagationDelay=0.000000E+000
|RECORD=2|OwnerIndex=28|OwnerPartId=1|FormalType=1|PinConglomerate=56|PinLength=30|Location.X=860|Location.Y=280|Name=NC|Designator=66|SwapIDPart=Ž&Ž||PinPropagationDelay=0.000000E+000
|RECORD=2|OwnerIndex=28|OwnerPartId=1|FormalType=1|PinConglomerate=56|PinLength=30|Location.X=860|Location.Y=320|Name=NC|Designator=60|SwapIDPart=Ž&Ž||PinPropagationDelay=0.000000E+000
|RECORD=2|OwnerIndex=28|OwnerPartId=1|FormalType=1|PinConglomerate=56|PinLength=30|Location.X=860|Location.Y=590|Name=UARTOUT_TX|Designator=64|SwapIDPart=Ž&Ž||PinPropagationDelay=0.000000E+000
|RECORD=2|OwnerIndex=28|OwnerPartId=1|FormalType=1|PinConglomerate=56|PinLength=30|Location.X=860|Location.Y=270|Name=NC|Designator=68|SwapIDPart=Ž&Ž||PinPropagationDelay=0.000000E+000
|RECORD=2|OwnerIndex=28|OwnerPartId=1|FormalType=1|PinConglomerate=58|PinLength=30|Location.X=710|Location.Y=500|Name=CONFIG_3(NC)|Designator=1|SwapIDPart=Ž&Ž||PinPropagationDelay=0.000000E+000
|RECORD=2|OwnerIndex=28|OwnerPartId=1|FormalType=1|PinConglomerate=58|PinLength=30|Location.X=710|Location.Y=570|Name=USB_DP|Designator=7|SwapIDPart=Ž&Ž||PinPropagationDelay=0.000000E+000
|RECORD=2|OwnerIndex=28|OwnerPartId=1|FormalType=1|PinConglomerate=58|PinLength=30|Location.X=710|Location.Y=560|Name=USB_DN|Designator=9|SwapIDPart=Ž&Ž||PinPropagationDelay=0.000000E+000
|RECORD=2|OwnerIndex=28|OwnerPartId=1|FormalType=1|PinConglomerate=56|PinLength=30|Location.X=860|Location.Y=560|Name=NC|Designator=23|SwapIDPart=Ž&Ž||PinPropagationDelay=0.000000E+000
|RECORD=2|OwnerIndex=28|OwnerPartId=1|FormalType=1|PinConglomerate=56|PinLength=30|Location.X=860|Location.Y=540|Name=NC|Designator=25|SwapIDPart=Ž&Ž||PinPropagationDelay=0.000000E+000
|RECORD=2|OwnerIndex=28|OwnerPartId=1|FormalType=1|PinConglomerate=56|PinLength=30|Location.X=860|Location.Y=510|Name=NC|Designator=29|SwapIDPart=Ž&Ž||PinPropagationDelay=0.000000E+000
|RECORD=2|OwnerIndex=28|OwnerPartId=1|FormalType=1|PinConglomerate=56|PinLength=30|Location.X=860|Location.Y=490|Name=NC|Designator=31|SwapIDPart=Ž&Ž||PinPropagationDelay=0.000000E+000
|RECORD=2|OwnerIndex=28|OwnerPartId=1|FormalType=1|PinConglomerate=56|PinLength=30|Location.X=860|Location.Y=450|Name=NC|Designator=37|SwapIDPart=Ž&Ž||PinPropagationDelay=0.000000E+000
|RECORD=2|OwnerIndex=28|OwnerPartId=1|FormalType=1|PinConglomerate=56|PinLength=30|Location.X=860|Location.Y=430|Name=NC|Designator=41|SwapIDPart=Ž&Ž||PinPropagationDelay=0.000000E+000
|RECORD=2|OwnerIndex=28|OwnerPartId=1|FormalType=1|PinConglomerate=56|PinLength=30|Location.X=860|Location.Y=420|Name=NC|Designator=43|SwapIDPart=Ž&Ž||PinPropagationDelay=0.000000E+000
|RECORD=2|OwnerIndex=28|OwnerPartId=1|FormalType=1|PinConglomerate=56|PinLength=30|Location.X=860|Location.Y=410|Name=NC|Designator=47|SwapIDPart=Ž&Ž||PinPropagationDelay=0.000000E+000
|RECORD=2|OwnerIndex=28|OwnerPartId=1|FormalType=1|PinConglomerate=56|PinLength=30|Location.X=860|Location.Y=400|Name=NC|Designator=49|SwapIDPart=Ž&Ž||PinPropagationDelay=0.000000E+000
|RECORD=2|OwnerIndex=28|OwnerPartId=1|FormalType=1|PinConglomerate=56|PinLength=30|Location.X=860|Location.Y=380|Name=NC|Designator=53|SwapIDPart=Ž&Ž||PinPropagationDelay=0.000000E+000
|RECORD=2|OwnerIndex=28|OwnerPartId=1|FormalType=1|PinConglomerate=56|PinLength=30|Location.X=860|Location.Y=360|Name=NC|Designator=55|SwapIDPart=Ž&Ž||PinPropagationDelay=0.000000E+000
|RECORD=2|OwnerIndex=28|OwnerPartId=1|FormalType=1|PinConglomerate=56|PinLength=30|Location.X=860|Location.Y=330|Name=NC|Designator=59|SwapIDPart=Ž&Ž||PinPropagationDelay=0.000000E+000
|RECORD=2|OwnerIndex=28|OwnerPartId=1|FormalType=1|PinConglomerate=56|PinLength=30|Location.X=860|Location.Y=310|Name=NC|Designator=61|SwapIDPart=Ž&Ž||PinPropagationDelay=0.000000E+000
|RECORD=2|OwnerIndex=28|OwnerPartId=1|FormalType=1|PinConglomerate=56|PinLength=30|Location.X=860|Location.Y=300|Name=NC|Designator=63|SwapIDPart=Ž&Ž||PinPropagationDelay=0.000000E+000
|RECORD=2|OwnerIndex=28|OwnerPartId=1|FormalType=1|PinConglomerate=56|PinLength=30|Location.X=860|Location.Y=290|Name=NC|Designator=65|SwapIDPart=Ž&Ž||PinPropagationDelay=0.000000E+000
|RECORD=2|OwnerIndex=28|OwnerPartId=1|FormalType=1|PinConglomerate=58|PinLength=30|Location.X=710|Location.Y=650|Name=RESET_L|Designator=67|SwapIDPart=Ž&Ž||PinPropagationDelay=0.000000E+000
|RECORD=2|OwnerIndex=28|OwnerPartId=1|FormalType=1|PinConglomerate=58|PinLength=30|Location.X=710|Location.Y=520|Name=CONFIG_1(NC)|Designator=69|SwapIDPart=Ž&Ž||PinPropagationDelay=0.000000E+000
|RECORD=34|OwnerIndex=28|IndexInSheet=-1|OwnerPartId=-1|Location.X=710|Location.Y=720|Color=8388608|FontID=1|Text=J1|Name=Designator|ReadOnlyState=1
|RECORD=41|OwnerIndex=28|IndexInSheet=-1|OwnerPartId=-1|Location.X=710|Location.Y=240|Color=8388608|FontID=1|Text=OCPTAP_M2_FINGERS|Name=Comment
|RECORD=44|OwnerIndex=28
|RECORD=45|OwnerIndex=166|IndexInSheet=-1|ModelName=OCPTAP M2 FINGERS|ModelType=PCBLIB|DatafileCount=1|ModelDatafileEntity0=OCPTAP M2 FINGERS|ModelDatafileKind0=PCBLib|IsCurrent=T
|RECORD=46|OwnerIndex=167
|RECORD=48|OwnerIndex=167
|RECORD=17|IndexInSheet=28|OwnerPartId=-1|Style=4|ShowNetName=F|Location.X=660|Location.Y=320|Orientation=3|Color=128|FontID=1|Text=GND
|RECORD=27|IndexInSheet=29|OwnerPartId=-1|LineWidth=1|Color=8388608|LocationCount=12|X1=680|Y1=430|X2=660|Y2=430|X3=660|Y3=420|X4=660|Y4=410|X5=660|Y5=400|X6=660|Y6=390|X7=660|Y7=380|X8=660|Y8=370|X9=660|Y9=360|X10=660|Y10=350|X11=660|Y11=340|X12=660|Y12=320
|RECORD=27|IndexInSheet=30|OwnerPartId=-1|LineWidth=1|Color=8388608|LocationCount=2|X1=680|Y1=340|X2=660|Y2=340
|RECORD=27|IndexInSheet=31|OwnerPartId=-1|LineWidth=1|Color=8388608|LocationCount=2|X1=680|Y1=350|X2=660|Y2=350
|RECORD=27|IndexInSheet=32|OwnerPartId=-1|LineWidth=1|Color=8388608|LocationCount=2|X1=680|Y1=360|X2=660|Y2=360
|RECORD=27|IndexInSheet=33|OwnerPartId=-1|LineWidth=1|Color=8388608|LocationCount=2|X1=680|Y1=370|X2=660|Y2=370
|RECORD=27|IndexInSheet=34|OwnerPartId=-1|LineWidth=1|Color=8388608|LocationCount=2|X1=680|Y1=380|X2=660|Y2=380
|RECORD=27|IndexInSheet=35|OwnerPartId=-1|LineWidth=1|Color=8388608|LocationCount=2|X1=680|Y1=390|X2=660|Y2=390
|RECORD=27|IndexInSheet=36|OwnerPartId=-1|LineWidth=1|Color=8388608|LocationCount=2|X1=680|Y1=400|X2=660|Y2=400
|RECORD=27|IndexInSheet=37|OwnerPartId=-1|LineWidth=1|Color=8388608|LocationCount=2|X1=680|Y1=410|X2=660|Y2=410
|RECORD=27|IndexInSheet=38|OwnerPartId=-1|LineWidth=1|Color=8388608|LocationCount=2|X1=680|Y1=420|X2=660|Y2=420
|RECORD=27|IndexInSheet=39|OwnerPartId=-1|LineWidth=1|Color=8388608|LocationCount=5|X1=680|Y1=530|X2=660|Y2=530|X3=660|Y3=510|X4=660|Y4=490|X5=660|Y5=430
|RECORD=27|IndexInSheet=40|OwnerPartId=-1|LineWidth=1|Color=8388608|LocationCount=2|X1=680|Y1=510|X2=660|Y2=510
|RECORD=27|IndexInSheet=41|OwnerPartId=-1|LineWidth=1|Color=8388608|LocationCount=2|X1=680|Y1=490|X2=660|Y2=490
|RECORD=17|IndexInSheet=42|OwnerPartId=-1|Style=2|ShowNetName=T|Location.X=660|Location.Y=770|Orientation=1|Color=128|FontID=1|Text=+3V3
|RECORD=27|IndexInSheet=43|OwnerPartId=-1|LineWidth=1|Color=8388608|LocationCount=2|X1=680|Y1=710|X2=660|Y2=710
|RECORD=27|IndexInSheet=44|OwnerPartId=-1|LineWidth=1|Color=8388608|LocationCount=2|X1=680|Y1=700|X2=660|Y2=700
|RECORD=27|IndexInSheet=45|OwnerPartId=-1|LineWidth=1|Color=8388608|LocationCount=2|X1=680|Y1=690|X2=660|Y2=690
|RECORD=27|IndexInSheet=46|OwnerPartId=-1|LineWidth=1|Color=8388608|LocationCount=2|X1=680|Y1=680|X2=660|Y2=680
|RECORD=17|IndexInSheet=47|OwnerPartId=-1|Style=1|ShowNetName=T|Location.X=540|Location.Y=650|Orientation=2|Color=255|FontID=1|Text=RST_GPS|IsCrossSheetConnector=T
|RECORD=17|IndexInSheet=48|OwnerPartId=-1|Style=1|ShowNetName=T|Location.X=930|Location.Y=600|Color=255|FontID=1|Text=RX_GPS_CONN|IsCrossSheetConnector=T
|RECORD=17|IndexInSheet=49|OwnerPartId=-1|ShowNetName=T|Location.X=930|Location.Y=590|Color=255|FontID=1|Text=TX_GPS_CONN|IsCrossSheetConnector=T
|RECORD=27|IndexInSheet=50|OwnerPartId=-1|LineWidth=1|Color=8388608|LocationCount=2|X1=890|Y1=600|X2=930|Y2=600
|RECORD=27|IndexInSheet=51|OwnerPartId=-1|LineWidth=1|Color=8388608|LocationCount=2|X1=890|Y1=590|X2=930|Y2=590
|RECORD=17|IndexInSheet=52|OwnerPartId=-1|ShowNetName=T|Location.X=640|Location.Y=570|Orientation=2|Color=255|FontID=1|Text=USB_D_P|IsCrossSheetConnector=T
|RECORD=17|IndexInSheet=53|OwnerPartId=-1|ShowNetName=T|Location.X=640|Location.Y=560|Orientation=2|Color=255|FontID=1|Text=USB_D_N|IsCrossSheetConnector=T
|RECORD=27|IndexInSheet=54|OwnerPartId=-1|LineWidth=1|Color=8388608|LocationCount=2|X1=640|Y1=560|X2=680|Y2=560
|RECORD=27|IndexInSheet=55|OwnerPartId=-1|LineWidth=1|Color=8388608|LocationCount=2|X1=640|Y1=570|X2=680|Y2=570
|RECORD=17|IndexInSheet=56|OwnerPartId=-1|ShowNetName=T|Location.X=600|Location.Y=610|Orientation=2|Color=255|FontID=1|Text=SDA|IsCrossSheetConnector=T
|RECORD=17|IndexInSheet=57|OwnerPartId=-1|ShowNetName=T|Location.X=600|Location.Y=620|Orientation=2|Color=255|FontID=1|Text=SCL|IsCrossSheetConnector=T
|RECORD=27|IndexInSheet=58|OwnerPartId=-1|LineWidth=1|Color=8388608|LocationCount=2|X1=600|Y1=610|X2=680|Y2=610
|RECORD=27|IndexInSheet=59|OwnerPartId=-1|LineWidth=1|Color=8388608|LocationCount=2|X1=600|Y1=620|X2=680|Y2=620
|RECORD=27|IndexInSheet=60|OwnerPartId=-1|LineWidth=1|Color=8388608|LocationCount=2|X1=680|Y1=640|X2=610|Y2=640
|RECORD=27|IndexInSheet=61|OwnerPartId=-1|LineWidth=1|Color=8388608|LocationCount=4|X1=680|Y1=650|X2=630|Y2=650|X3=630|Y3=670|X4=610|Y4=670
|RECORD=27|IndexInSheet=62|OwnerPartId=-1|LineWidth=1|Color=8388608|LocationCount=4|X1=570|Y1=670|X2=560|Y2=670|X3=560|Y3=650|X4=540|Y4=650
|RECORD=27|IndexInSheet=63|OwnerPartId=-1|LineWidth=1|Color=8388608|LocationCount=3|X1=570|Y1=640|X2=560|Y2=640|X3=560|Y3=650
|RECORD=1|LibReference=02cd4be3c70576c341d710602a673aa|ComponentDescription=Chip Multilayer Ceramic Capacitors for General Purpose, 1206, 47uF, X5R, 15%, 20%, 6.3V|PartCount=2|DisplayModeCount=1|IndexInSheet=64|OwnerPartId=-1|Location.X=540|Location.Y=730|CurrentPartId=1|LibraryPath=*|SourceLibraryName=Altium Content Vault|TargetFileName=*|AreaColor=11599871|Color=128|PartIDLocked=T|DesignItemId=CMP-2000-06344-2|AllPinCount=2
|RECORD=2|OwnerIndex=206|OwnerPartId=1|Electrical=4|PinConglomerate=49|PinLength=7|Location.X=540|Location.Y=723|Name=1|Designator=1|PinPropagationDelay=0.000000E+000
|RECORD=2|OwnerIndex=206|OwnerPartId=1|Electrical=4|PinConglomerate=51|PinLength=6|Location.X=540|Location.Y=716|Name=2|Designator=2|PinPropagationDelay=0.000000E+000
|RECORD=13|OwnerIndex=206|IsNotAccesible=T|IndexInSheet=2|OwnerPartId=1|Location.X=550|Location.Y=723|Corner.X=530|Corner.Y=723|LineWidth=1|Color=16711680
|RECORD=13|OwnerIndex=206|IsNotAccesible=T|IndexInSheet=3|OwnerPartId=1|Location.X=550|Location.Y=717|Corner.X=530|Corner.Y=717|LineWidth=1|Color=16711680
|RECORD=13|OwnerIndex=206|IsNotAccesible=T|IndexInSheet=4|OwnerPartId=1|Location.X=540|Location.Y=723|Corner.X=540|Corner.Y=726|LineWidth=1|Color=16711680
|RECORD=13|OwnerIndex=206|IsNotAccesible=T|IndexInSheet=5|OwnerPartId=1|Location.X=540|Location.Y=716|Corner.X=540|Corner.Y=715|LineWidth=1|Color=16711680
|RECORD=41|OwnerIndex=206|IndexInSheet=6|OwnerPartId=-1|Location.X=529|Location.Y=732|Color=8388608|FontID=1|IsHidden=T|Text=2000|Name=Package Quantity
|RECORD=41|OwnerIndex=206|IndexInSheet=7|OwnerPartId=-1|Location.X=529|Location.Y=732|Color=8388608|FontID=1|IsHidden=T|Text=Surface Mount|Name=Mount
|RECORD=41|OwnerIndex=206|IndexInSheet=8|OwnerPartId=-1|Location.X=529|Location.Y=732|Color=8388608|FontID=1|IsHidden=T|Text=3.2mm|Name=Length
|RECORD=41|OwnerIndex=206|IndexInSheet=9|OwnerPartId=-1|Location.X=529|Location.Y=732|Color=8388608|FontID=1|IsHidden=T|Text=0.071inch|Name=Thickness
|RECORD=41|OwnerIndex=206|IndexInSheet=10|OwnerPartId=-1|Location.X=529|Location.Y=732|Color=8388608|FontID=1|IsHidden=T|Text=Lead Free|Name=Lead Free
|RECORD=41|OwnerIndex=206|IndexInSheet=11|OwnerPartId=-1|Location.X=529|Location.Y=732|Color=8388608|FontID=1|IsHidden=T|Text=20%|Name=Tolerance
|RECORD=41|OwnerIndex=206|IndexInSheet=12|OwnerPartId=-1|Location.X=529|Location.Y=732|Color=8388608|FontID=1|IsHidden=T|Text=0.063inch|Name=Width
|RECORD=41|OwnerIndex=206|IndexInSheet=13|OwnerPartId=-1|Location.X=529|Location.Y=732|Color=8388608|FontID=1|IsHidden=T|Text=1.6mm|Name=Depth
|RECORD=41|OwnerIndex=206|IndexInSheet=14|OwnerPartId=-1|Location.X=529|Location.Y=732|Color=8388608|FontID=1|IsHidden=T|Text=1206|Name=Case/Package
|RECORD=41|OwnerIndex=206|IndexInSheet=15|OwnerPartId=-1|Location.X=529|Location.Y=732|Color=8388608|FontID=1|IsHidden=T|Text=X5R|Name=Dielectric
|RECORD=41|OwnerIndex=206|IndexInSheet=16|OwnerPartId=-1|Location.X=529|Location.Y=732|Color=8388608|FontID=1|IsHidden=T|Text=No|Name=Radiation Hardening
|RECORD=41|OwnerIndex=206|IndexInSheet=17|OwnerPartId=-1|Location.X=529|Location.Y=732|Color=8388608|FontID=1|IsHidden=T|Text=Tape and Reel|Name=Packaging
|RECORD=41|OwnerIndex=206|IndexInSheet=18|OwnerPartId=-1|Location.X=529|Location.Y=732|Color=8388608|FontID=1|IsHidden=T|Text=6.3V|Name=Voltage Rating (DC)
|RECORD=41|OwnerIndex=206|IndexInSheet=19|OwnerPartId=-1|Location.X=529|Location.Y=732|Color=8388608|FontID=1|IsHidden=T|Text=SMD/SMT|Name=Termination
|RECORD=41|OwnerIndex=206|IndexInSheet=20|OwnerPartId=-1|Location.X=529|Location.Y=732|Color=8388608|FontID=1|IsHidden=T|Text=1.6mm|Name=Height
|RECORD=41|OwnerIndex=206|IndexInSheet=21|OwnerPartId=-1|Location.X=529|Location.Y=732|Color=8388608|FontID=1|IsHidden=T|Text=85°C|Name=Max Operating Temperature
|RECORD=41|OwnerIndex=206|IndexInSheet=22|OwnerPartId=-1|Location.X=529|Location.Y=732|Color=8388608|FontID=1|IsHidden=T|Text=3216|Name=Case Code (Metric)
|RECORD=41|OwnerIndex=206|IndexInSheet=23|OwnerPartId=-1|Location.X=529|Location.Y=732|Color=8388608|FontID=1|IsHidden=T|Text=1206|Name=Case Code (Imperial)
|RECORD=41|OwnerIndex=206|IndexInSheet=24|OwnerPartId=-1|Location.X=529|Location.Y=732|Color=8388608|FontID=1|IsHidden=T|Text=6.3V|Name=Voltage
|RECORD=41|OwnerIndex=206|IndexInSheet=25|OwnerPartId=-1|Location.X=529|Location.Y=732|Color=8388608|FontID=1|IsHidden=T|Text=6.3V|Name=Voltage Rating
|RECORD=41|OwnerIndex=206|IndexInSheet=26|OwnerPartId=-1|Location.X=529|Location.Y=732|Color=8388608|FontID=1|IsHidden=T|Text=47uF|Name=Capacitance
|RECORD=41|OwnerIndex=206|IndexInSheet=27|OwnerPartId=-1|Location.X=529|Location.Y=732|Color=8388608|FontID=1|IsHidden=T|Text=-55°C|Name=Min Operating Temperature
|RECORD=41|OwnerIndex=206|IndexInSheet=28|OwnerPartId=-1|Location.X=529|Location.Y=732|Color=8388608|FontID=1|IsHidden=T|Text=Ceramic|Name=Material
|RECORD=41|OwnerIndex=206|IndexInSheet=29|OwnerPartId=-1|Location.X=529|Location.Y=732|Color=8388608|FontID=1|IsHidden=T|Text=No SVHC|Name=REACH SVHC
|RECORD=34|OwnerIndex=206|IndexInSheet=-1|OwnerPartId=-1|Location.X=530|Location.Y=710|Orientation=1|Color=8388608|FontID=2|Text=C6|Name=Designator|ReadOnlyState=1
|RECORD=41|OwnerIndex=206|IndexInSheet=-1|OwnerPartId=1|Location.X=560|Location.Y=690|Orientation=1|Color=8388608|FontID=2|Text=47uF_6.3V_1206|Name=Comment
|RECORD=44|OwnerIndex=206
|RECORD=45|OwnerIndex=241|IndexInSheet=-1|UseComponentLibrary=T|ModelName=FP-GRM31C-0_2-e0_3_0_8-IPC_C|ModelType=PCBLIB|DatafileCount=1|ModelDatafileEntity0=FP-GRM31C-0_2-e0_3_0_8-IPC_C|ModelDatafileKind0=PCBLib|IsCurrent=T|DatalinksLocked=T|DatabaseDatalinksLocked=T
|RECORD=46|OwnerIndex=242
|RECORD=48|OwnerIndex=242
|RECORD=45|OwnerIndex=241|IndexInSheet=-1|UseComponentLibrary=T|ModelName=FP-GRM31C-0_2-e0_3_0_8-IPC_A|ModelType=PCBLIB|DatafileCount=1|ModelDatafileEntity0=FP-GRM31C-0_2-e0_3_0_8-IPC_A|ModelDatafileKind0=PCBLib|DatalinksLocked=T|DatabaseDatalinksLocked=T
|RECORD=46|OwnerIndex=245
|RECORD=48|OwnerIndex=245
|RECORD=45|OwnerIndex=241|IndexInSheet=-1|UseComponentLibrary=T|ModelName=FP-GRM31C-0_2-e0_3_0_8-IPC_B|ModelType=PCBLIB|DatafileCount=1|ModelDatafileEntity0=FP-GRM31C-0_2-e0_3_0_8-IPC_B|ModelDatafileKind0=PCBLib|DatalinksLocked=T|DatabaseDatalinksLocked=T
|RECORD=46|OwnerIndex=248
|RECORD=48|OwnerIndex=248
|RECORD=45|OwnerIndex=241|IndexInSheet=-1|UseComponentLibrary=T|ModelName=FP-GRM31C-0_2-e0_3_0_8-MFG|ModelType=PCBLIB|DatafileCount=1|ModelDatafileEntity0=FP-GRM31C-0_2-e0_3_0_8-MFG|ModelDatafileKind0=PCBLib|DatalinksLocked=T|DatabaseDatalinksLocked=T
|RECORD=46|OwnerIndex=251
|RECORD=48|OwnerIndex=251
|RECORD=1|LibReference=02cd4be3c70576c341d710602a673aa|ComponentDescription=Chip Multilayer Ceramic Capacitors for General Purpose, 1206, 47uF, X5R, 15%, 20%, 6.3V|PartCount=2|DisplayModeCount=1|IndexInSheet=65|OwnerPartId=-1|Location.X=580|Location.Y=730|CurrentPartId=1|LibraryPath=*|SourceLibraryName=Altium Content Vault|TargetFileName=*|AreaColor=11599871|Color=128|PartIDLocked=T|DesignItemId=CMP-2000-06344-2|AllPinCount=2
|RECORD=2|OwnerIndex=254|OwnerPartId=1|Electrical=4|PinConglomerate=49|PinLength=7|Location.X=580|Location.Y=723|Name=1|Designator=1|PinPropagationDelay=0.000000E+000
|RECORD=2|OwnerIndex=254|OwnerPartId=1|Electrical=4|PinConglomerate=51|PinLength=6|Location.X=580|Location.Y=716|Name=2|Designator=2|PinPropagationDelay=0.000000E+000
|RECORD=13|OwnerIndex=254|IsNotAccesible=T|IndexInSheet=2|OwnerPartId=1|Location.X=590|Location.Y=723|Corner.X=570|Corner.Y=723|LineWidth=1|Color=16711680
|RECORD=13|OwnerIndex=254|IsNotAccesible=T|IndexInSheet=3|OwnerPartId=1|Location.X=590|Location.Y=717|Corner.X=570|Corner.Y=717|LineWidth=1|Color=16711680
|RECORD=13|OwnerIndex=254|IsNotAccesible=T|IndexInSheet=4|OwnerPartId=1|Location.X=580|Location.Y=723|Corner.X=580|Corner.Y=726|LineWidth=1|Color=16711680
|RECORD=13|OwnerIndex=254|IsNotAccesible=T|IndexInSheet=5|OwnerPartId=1|Location.X=580|Location.Y=716|Corner.X=580|Corner.Y=715|LineWidth=1|Color=16711680
|RECORD=41|OwnerIndex=254|IndexInSheet=6|OwnerPartId=-1|Location.X=569|Location.Y=732|Color=8388608|FontID=1|IsHidden=T|Text=2000|Name=Package Quantity
|RECORD=41|OwnerIndex=254|IndexInSheet=7|OwnerPartId=-1|Location.X=569|Location.Y=732|Color=8388608|FontID=1|IsHidden=T|Text=Surface Mount|Name=Mount
|RECORD=41|OwnerIndex=254|IndexInSheet=8|OwnerPartId=-1|Location.X=569|Location.Y=732|Color=8388608|FontID=1|IsHidden=T|Text=3.2mm|Name=Length
|RECORD=41|OwnerIndex=254|IndexInSheet=9|OwnerPartId=-1|Location.X=569|Location.Y=732|Color=8388608|FontID=1|IsHidden=T|Text=0.071inch|Name=Thickness
|RECORD=41|OwnerIndex=254|IndexInSheet=10|OwnerPartId=-1|Location.X=569|Location.Y=732|Color=8388608|FontID=1|IsHidden=T|Text=Lead Free|Name=Lead Free
|RECORD=41|OwnerIndex=254|IndexInSheet=11|OwnerPartId=-1|Location.X=569|Location.Y=732|Color=8388608|FontID=1|IsHidden=T|Text=20%|Name=Tolerance
|RECORD=41|OwnerIndex=254|IndexInSheet=12|OwnerPartId=-1|Location.X=569|Location.Y=732|Color=8388608|FontID=1|IsHidden=T|Text=0.063inch|Name=Width
|RECORD=41|OwnerIndex=254|IndexInSheet=13|OwnerPartId=-1|Location.X=569|Location.Y=732|Color=8388608|FontID=1|IsHidden=T|Text=1.6mm|Name=Depth
|RECORD=41|OwnerIndex=254|IndexInSheet=14|OwnerPartId=-1|Location.X=569|Location.Y=732|Color=8388608|FontID=1|IsHidden=T|Text=1206|Name=Case/Package
|RECORD=41|OwnerIndex=254|IndexInSheet=15|OwnerPartId=-1|Location.X=569|Location.Y=732|Color=8388608|FontID=1|IsHidden=T|Text=X5R|Name=Dielectric
|RECORD=41|OwnerIndex=254|IndexInSheet=16|OwnerPartId=-1|Location.X=569|Location.Y=732|Color=8388608|FontID=1|IsHidden=T|Text=No|Name=Radiation Hardening
|RECORD=41|OwnerIndex=254|IndexInSheet=17|OwnerPartId=-1|Location.X=569|Location.Y=732|Color=8388608|FontID=1|IsHidden=T|Text=Tape and Reel|Name=Packaging
|RECORD=41|OwnerIndex=254|IndexInSheet=18|OwnerPartId=-1|Location.X=569|Location.Y=732|Color=8388608|FontID=1|IsHidden=T|Text=6.3V|Name=Voltage Rating (DC)
|RECORD=41|OwnerIndex=254|IndexInSheet=19|OwnerPartId=-1|Location.X=569|Location.Y=732|Color=8388608|FontID=1|IsHidden=T|Text=SMD/SMT|Name=Termination
|RECORD=41|OwnerIndex=254|IndexInSheet=20|OwnerPartId=-1|Location.X=569|Location.Y=732|Color=8388608|FontID=1|IsHidden=T|Text=1.6mm|Name=Height
|RECORD=41|OwnerIndex=254|IndexInSheet=21|OwnerPartId=-1|Location.X=569|Location.Y=732|Color=8388608|FontID=1|IsHidden=T|Text=85°C|Name=Max Operating Temperature
|RECORD=41|OwnerIndex=254|IndexInSheet=22|OwnerPartId=-1|Location.X=569|Location.Y=732|Color=8388608|FontID=1|IsHidden=T|Text=3216|Name=Case Code (Metric)
|RECORD=41|OwnerIndex=254|IndexInSheet=23|OwnerPartId=-1|Location.X=569|Location.Y=732|Color=8388608|FontID=1|IsHidden=T|Text=1206|Name=Case Code (Imperial)
|RECORD=41|OwnerIndex=254|IndexInSheet=24|OwnerPartId=-1|Location.X=569|Location.Y=732|Color=8388608|FontID=1|IsHidden=T|Text=6.3V|Name=Voltage
|RECORD=41|OwnerIndex=254|IndexInSheet=25|OwnerPartId=-1|Location.X=569|Location.Y=732|Color=8388608|FontID=1|IsHidden=T|Text=6.3V|Name=Voltage Rating
|RECORD=41|OwnerIndex=254|IndexInSheet=26|OwnerPartId=-1|Location.X=569|Location.Y=732|Color=8388608|FontID=1|IsHidden=T|Text=47uF|Name=Capacitance
|RECORD=41|OwnerIndex=254|IndexInSheet=27|OwnerPartId=-1|Location.X=569|Location.Y=732|Color=8388608|FontID=1|IsHidden=T|Text=-55°C|Name=Min Operating Temperature
|RECORD=41|OwnerIndex=254|IndexInSheet=28|OwnerPartId=-1|Location.X=569|Location.Y=732|Color=8388608|FontID=1|IsHidden=T|Text=Ceramic|Name=Material
|RECORD=41|OwnerIndex=254|IndexInSheet=29|OwnerPartId=-1|Location.X=569|Location.Y=732|Color=8388608|FontID=1|IsHidden=T|Text=No SVHC|Name=REACH SVHC
|RECORD=34|OwnerIndex=254|IndexInSheet=-1|OwnerPartId=-1|Location.X=570|Location.Y=710|Orientation=1|Color=8388608|FontID=2|Text=C7|Name=Designator|ReadOnlyState=1
|RECORD=41|OwnerIndex=254|IndexInSheet=-1|OwnerPartId=1|Location.X=600|Location.Y=690|Orientation=1|Color=8388608|FontID=2|Text=47uF_6.3V_1206|Name=Comment
|RECORD=44|OwnerIndex=254
|RECORD=45|OwnerIndex=289|IndexInSheet=-1|UseComponentLibrary=T|ModelName=FP-GRM31C-0_2-e0_3_0_8-IPC_C|ModelType=PCBLIB|DatafileCount=1|ModelDatafileEntity0=FP-GRM31C-0_2-e0_3_0_8-IPC_C|ModelDatafileKind0=PCBLib|IsCurrent=T|DatalinksLocked=T|DatabaseDatalinksLocked=T
|RECORD=46|OwnerIndex=290
|RECORD=48|OwnerIndex=290
|RECORD=45|OwnerIndex=289|IndexInSheet=-1|UseComponentLibrary=T|ModelName=FP-GRM31C-0_2-e0_3_0_8-IPC_A|ModelType=PCBLIB|DatafileCount=1|ModelDatafileEntity0=FP-GRM31C-0_2-e0_3_0_8-IPC_A|ModelDatafileKind0=PCBLib|DatalinksLocked=T|DatabaseDatalinksLocked=T
|RECORD=46|OwnerIndex=293
|RECORD=48|OwnerIndex=293
|RECORD=45|OwnerIndex=289|IndexInSheet=-1|UseComponentLibrary=T|ModelName=FP-GRM31C-0_2-e0_3_0_8-IPC_B|ModelType=PCBLIB|DatafileCount=1|ModelDatafileEntity0=FP-GRM31C-0_2-e0_3_0_8-IPC_B|ModelDatafileKind0=PCBLib|DatalinksLocked=T|DatabaseDatalinksLocked=T
|RECORD=46|OwnerIndex=296
|RECORD=48|OwnerIndex=296
|RECORD=45|OwnerIndex=289|IndexInSheet=-1|UseComponentLibrary=T|ModelName=FP-GRM31C-0_2-e0_3_0_8-MFG|ModelType=PCBLIB|DatafileCount=1|ModelDatafileEntity0=FP-GRM31C-0_2-e0_3_0_8-MFG|ModelDatafileKind0=PCBLib|DatalinksLocked=T|DatabaseDatalinksLocked=T
|RECORD=46|OwnerIndex=299
|RECORD=48|OwnerIndex=299
|RECORD=27|IndexInSheet=66|OwnerPartId=-1|LineWidth=1|Color=8388608|LocationCount=8|X1=680|Y1=670|X2=660|Y2=670|X3=660|Y3=680|X4=660|Y4=690|X5=660|Y5=700|X6=660|Y6=710|X7=660|Y7=760|X8=660|Y8=770
|RECORD=27|IndexInSheet=67|OwnerPartId=-1|LineWidth=1|Color=8388608|LocationCount=4|X1=660|Y1=760|X2=580|Y2=760|X3=540|Y3=760|X4=540|Y4=730
|RECORD=27|IndexInSheet=68|OwnerPartId=-1|LineWidth=1|Color=8388608|LocationCount=2|X1=580|Y1=730|X2=580|Y2=760
|RECORD=17|IndexInSheet=69|OwnerPartId=-1|Style=4|ShowNetName=F|Location.X=540|Location.Y=680|Orientation=3|Color=128|FontID=1|Text=GND
|RECORD=27|IndexInSheet=70|OwnerPartId=-1|LineWidth=1|Color=8388608|LocationCount=3|X1=540|Y1=680|X2=540|Y2=690|X3=540|Y3=710
|RECORD=27|IndexInSheet=71|OwnerPartId=-1|LineWidth=1|Color=8388608|LocationCount=3|X1=580|Y1=710|X2=580|Y2=690|X3=540|Y3=690
|RECORD=1|LibReference=RES|PartCount=2|DisplayModeCount=2|IndexInSheet=72|OwnerPartId=-1|Location.X=580|Location.Y=680|CurrentPartId=1|SourceLibraryName=Altium Content Vault|TargetFileName=*|AreaColor=11599871|Color=128|PartIDLocked=F|DesignItemId=CMP-2002-06457-1|AllPinCount=2
|RECORD=2|OwnerIndex=308|OwnerPartId=1|OwnerPartDisplayMode=1|FormalType=1|Electrical=4|PinConglomerate=32|PinLength=10|Location.X=600|Location.Y=670|Name=2|Designator=2|PinPropagationDelay=0.000000E+000
|RECORD=2|OwnerIndex=308|OwnerPartId=1|OwnerPartDisplayMode=1|FormalType=1|Electrical=4|PinConglomerate=34|PinLength=10|Location.X=580|Location.Y=670|Name=1|Designator=1|PinPropagationDelay=0.000000E+000
|RECORD=14|OwnerIndex=308|IsNotAccesible=T|IndexInSheet=2|OwnerPartId=1|OwnerPartDisplayMode=1|Location.X=580|Location.Y=666|Corner.X=600|Corner.Y=674|LineWidth=1|Color=16711680|AreaColor=11599871
|RECORD=2|OwnerIndex=308|OwnerPartId=1|FormalType=1|Electrical=4|PinConglomerate=32|PinLength=10|Location.X=600|Location.Y=670|Name=2|Designator=2|PinPropagationDelay=0.000000E+000
|RECORD=2|OwnerIndex=308|OwnerPartId=1|FormalType=1|Electrical=4|PinConglomerate=34|PinLength=10|Location.X=580|Location.Y=670|Name=1|Designator=1|PinPropagationDelay=0.000000E+000
|RECORD=6|OwnerIndex=308|IsNotAccesible=T|IndexInSheet=5|OwnerPartId=1|LineWidth=1|Color=16711680|LocationCount=10|X1=600|Y1=670|X2=596|Y2=670|X3=595|Y3=668|X4=593|Y4=672|X5=591|Y5=668|X6=589|Y6=672|X7=587|Y7=668|X8=585|Y8=672|X9=584|Y9=670|X10=580|Y10=670
|RECORD=41|OwnerIndex=308|IndexInSheet=6|OwnerPartId=-1|Location.X=568|Location.Y=683|Color=8388608|FontID=1|IsHidden=T|Text=Panasonic|Name=Manufacturer
|RECORD=41|OwnerIndex=308|IndexInSheet=7|OwnerPartId=-1|Location.X=568|Location.Y=683|Color=8388608|FontID=1|IsHidden=T|Text=ERJ-U020R00X|Name=Part Number
|RECORD=34|OwnerIndex=308|IndexInSheet=-1|OwnerPartId=-1|Location.X=579|Location.Y=673|Color=8388608|FontID=1|Text=R12|Name=Designator|ReadOnlyState=1
|RECORD=41|OwnerIndex=308|IndexInSheet=-1|OwnerPartId=-1|Location.X=579|Location.Y=657|Color=8388608|FontID=1|Text=0_5%_0402|Name=Comment
|RECORD=44|OwnerIndex=308
|RECORD=45|OwnerIndex=323|IndexInSheet=-1|Description=Chip Resistor, 2-Leads, Body 1.00x0.50mm, IPC Medium Density|UseComponentLibrary=T|ModelName=RESC1005X40X25NL05T10|ModelType=PCBLIB|DatafileCount=1|ModelDatafileEntity0=RESC1005X40X25NL05T10|ModelDatafileKind0=PCBLib|IsCurrent=T|DatalinksLocked=T|DatabaseDatalinksLocked=T
|RECORD=46|OwnerIndex=324
|RECORD=48|OwnerIndex=324
|RECORD=41|OwnerIndex=326|IndexInSheet=-1|OwnerPartId=-1|Color=8388608|FontID=1|IsHidden=T|Text=2D|Name=Available Preview Images
|RECORD=45|OwnerIndex=323|IndexInSheet=-1|Description=Chip Resistor, 2-Leads, Body 1.00x0.50mm, IPC High Density|UseComponentLibrary=T|ModelName=RESC1005X40X25LL05T10|ModelType=PCBLIB|DatafileCount=1|ModelDatafileEntity0=RESC1005X40X25LL05T10|ModelDatafileKind0=PCBLib|DatalinksLocked=T|DatabaseDatalinksLocked=T
|RECORD=46|OwnerIndex=328
|RECORD=48|OwnerIndex=328
|RECORD=41|OwnerIndex=330|IndexInSheet=-1|OwnerPartId=-1|Color=8388608|FontID=1|IsHidden=T|Text=2D|Name=Available Preview Images
|RECORD=45|OwnerIndex=323|IndexInSheet=-1|Description=Chip Resistor, 2-Leads, Body 1.00x0.50mm, IPC Low Density|UseComponentLibrary=T|ModelName=RESC1005X40X25ML05T10|ModelType=PCBLIB|DatafileCount=1|ModelDatafileEntity0=RESC1005X40X25ML05T10|ModelDatafileKind0=PCBLib|DatalinksLocked=T|DatabaseDatalinksLocked=T
|RECORD=46|OwnerIndex=332
|RECORD=48|OwnerIndex=332
|RECORD=41|OwnerIndex=334|IndexInSheet=-1|OwnerPartId=-1|Color=8388608|FontID=1|IsHidden=T|Text=2D|Name=Available Preview Images
|RECORD=1|LibReference=RES|PartCount=2|DisplayModeCount=2|IndexInSheet=73|OwnerPartId=-1|Location.X=580|Location.Y=650|CurrentPartId=1|SourceLibraryName=Altium Content Vault|TargetFileName=*|AreaColor=11599871|Color=128|PartIDLocked=F|DesignItemId=CMP-2002-06457-1|AllPinCount=2
|RECORD=2|OwnerIndex=336|OwnerPartId=1|OwnerPartDisplayMode=1|FormalType=1|Electrical=4|PinConglomerate=32|PinLength=10|Location.X=600|Location.Y=640|Name=2|Designator=2|PinPropagationDelay=0.000000E+000
|RECORD=2|OwnerIndex=336|OwnerPartId=1|OwnerPartDisplayMode=1|FormalType=1|Electrical=4|PinConglomerate=34|PinLength=10|Location.X=580|Location.Y=640|Name=1|Designator=1|PinPropagationDelay=0.000000E+000
|RECORD=14|OwnerIndex=336|IsNotAccesible=T|IndexInSheet=2|OwnerPartId=1|OwnerPartDisplayMode=1|Location.X=580|Location.Y=636|Corner.X=600|Corner.Y=644|LineWidth=1|Color=16711680|AreaColor=11599871
|RECORD=2|OwnerIndex=336|OwnerPartId=1|FormalType=1|Electrical=4|PinConglomerate=32|PinLength=10|Location.X=600|Location.Y=640|Name=2|Designator=2|PinPropagationDelay=0.000000E+000
|RECORD=2|OwnerIndex=336|OwnerPartId=1|FormalType=1|Electrical=4|PinConglomerate=34|PinLength=10|Location.X=580|Location.Y=640|Name=1|Designator=1|PinPropagationDelay=0.000000E+000
|RECORD=6|OwnerIndex=336|IsNotAccesible=T|IndexInSheet=5|OwnerPartId=1|LineWidth=1|Color=16711680|LocationCount=10|X1=600|Y1=640|X2=596|Y2=640|X3=595|Y3=638|X4=593|Y4=642|X5=591|Y5=638|X6=589|Y6=642|X7=587|Y7=638|X8=585|Y8=642|X9=584|Y9=640|X10=580|Y10=640
|RECORD=41|OwnerIndex=336|IndexInSheet=6|OwnerPartId=-1|Location.X=568|Location.Y=653|Color=8388608|FontID=1|IsHidden=T|Text=Panasonic|Name=Manufacturer
|RECORD=41|OwnerIndex=336|IndexInSheet=7|OwnerPartId=-1|Location.X=568|Location.Y=653|Color=8388608|FontID=1|IsHidden=T|Text=ERJ-U020R00X|Name=Part Number
|RECORD=34|OwnerIndex=336|IndexInSheet=-1|OwnerPartId=-1|Location.X=579|Location.Y=643|Color=8388608|FontID=1|Text=R13|Name=Designator|ReadOnlyState=1
|RECORD=41|OwnerIndex=336|IndexInSheet=-1|OwnerPartId=-1|Location.X=579|Location.Y=627|Color=8388608|FontID=1|Text=0_5%_0402|Name=Comment
|RECORD=44|OwnerIndex=336
|RECORD=45|OwnerIndex=351|IndexInSheet=-1|Description=Chip Resistor, 2-Leads, Body 1.00x0.50mm, IPC Medium Density|UseComponentLibrary=T|ModelName=RESC1005X40X25NL05T10|ModelType=PCBLIB|DatafileCount=1|ModelDatafileEntity0=RESC1005X40X25NL05T10|ModelDatafileKind0=PCBLib|IsCurrent=T|DatalinksLocked=T|DatabaseDatalinksLocked=T
|RECORD=46|OwnerIndex=352
|RECORD=48|OwnerIndex=352
|RECORD=41|OwnerIndex=354|IndexInSheet=-1|OwnerPartId=-1|Color=8388608|FontID=1|IsHidden=T|Text=2D|Name=Available Preview Images
|RECORD=45|OwnerIndex=351|IndexInSheet=-1|Description=Chip Resistor, 2-Leads, Body 1.00x0.50mm, IPC High Density|UseComponentLibrary=T|ModelName=RESC1005X40X25LL05T10|ModelType=PCBLIB|DatafileCount=1|ModelDatafileEntity0=RESC1005X40X25LL05T10|ModelDatafileKind0=PCBLib|DatalinksLocked=T|DatabaseDatalinksLocked=T
|RECORD=46|OwnerIndex=356
|RECORD=48|OwnerIndex=356
|RECORD=41|OwnerIndex=358|IndexInSheet=-1|OwnerPartId=-1|Color=8388608|FontID=1|IsHidden=T|Text=2D|Name=Available Preview Images
|RECORD=45|OwnerIndex=351|IndexInSheet=-1|Description=Chip Resistor, 2-Leads, Body 1.00x0.50mm, IPC Low Density|UseComponentLibrary=T|ModelName=RESC1005X40X25ML05T10|ModelType=PCBLIB|DatafileCount=1|ModelDatafileEntity0=RESC1005X40X25ML05T10|ModelDatafileKind0=PCBLib|DatalinksLocked=T|DatabaseDatalinksLocked=T
|RECORD=46|OwnerIndex=360
|RECORD=48|OwnerIndex=360
|RECORD=41|OwnerIndex=362|IndexInSheet=-1|OwnerPartId=-1|Color=8388608|FontID=1|IsHidden=T|Text=2D|Name=Available Preview Images
|RECORD=1|LibReference=RES|PartCount=2|DisplayModeCount=2|IndexInSheet=74|OwnerPartId=-1|Location.X=960|Location.Y=640|CurrentPartId=1|SourceLibraryName=Altium Content Vault|TargetFileName=*|AreaColor=11599871|Color=128|PartIDLocked=F|DesignItemId=CMP-2002-06457-1|AllPinCount=2|ComponentKindVersion2=5
|RECORD=2|OwnerIndex=364|OwnerPartId=1|OwnerPartDisplayMode=1|FormalType=1|Electrical=4|PinConglomerate=32|PinLength=10|Location.X=980|Location.Y=630|Name=2|Designator=2|PinPropagationDelay=0.000000E+000
|RECORD=2|OwnerIndex=364|OwnerPartId=1|OwnerPartDisplayMode=1|FormalType=1|Electrical=4|PinConglomerate=34|PinLength=10|Location.X=960|Location.Y=630|Name=1|Designator=1|PinPropagationDelay=0.000000E+000
|RECORD=14|OwnerIndex=364|IsNotAccesible=T|IndexInSheet=2|OwnerPartId=1|OwnerPartDisplayMode=1|Location.X=960|Location.Y=626|Corner.X=980|Corner.Y=634|LineWidth=1|Color=16711680|AreaColor=11599871
|RECORD=2|OwnerIndex=364|OwnerPartId=1|FormalType=1|Electrical=4|PinConglomerate=32|PinLength=10|Location.X=980|Location.Y=630|Name=2|Designator=2|PinPropagationDelay=0.000000E+000
|RECORD=2|OwnerIndex=364|OwnerPartId=1|FormalType=1|Electrical=4|PinConglomerate=34|PinLength=10|Location.X=960|Location.Y=630|Name=1|Designator=1|PinPropagationDelay=0.000000E+000
|RECORD=6|OwnerIndex=364|IsNotAccesible=T|IndexInSheet=5|OwnerPartId=1|LineWidth=1|Color=16711680|LocationCount=10|X1=980|Y1=630|X2=976|Y2=630|X3=975|Y3=628|X4=973|Y4=632|X5=971|Y5=628|X6=969|Y6=632|X7=967|Y7=628|X8=965|Y8=632|X9=964|Y9=630|X10=960|Y10=630
|RECORD=41|OwnerIndex=364|IndexInSheet=6|OwnerPartId=-1|Location.X=948|Location.Y=643|Color=8388608|FontID=1|IsHidden=T|Text=Panasonic|Name=Manufacturer
|RECORD=41|OwnerIndex=364|IndexInSheet=7|OwnerPartId=-1|Location.X=948|Location.Y=643|Color=8388608|FontID=1|IsHidden=T|Text=ERJ-U020R00X|Name=Part Number
|RECORD=34|OwnerIndex=364|IndexInSheet=-1|OwnerPartId=-1|Location.X=940|Location.Y=630|Color=8388608|FontID=1|Text=R14|Name=Designator|ReadOnlyState=1
|RECORD=41|OwnerIndex=364|IndexInSheet=-1|OwnerPartId=-1|Location.X=980|Location.Y=630|Color=8388608|FontID=1|Text=DNI_0_5%_0402|Name=Comment
|RECORD=44|OwnerIndex=364
|RECORD=45|OwnerIndex=379|IndexInSheet=-1|Description=Chip Resistor, 2-Leads, Body 1.00x0.50mm, IPC Medium Density|UseComponentLibrary=T|ModelName=RESC1005X40X25NL05T10|ModelType=PCBLIB|DatafileCount=1|ModelDatafileEntity0=RESC1005X40X25NL05T10|ModelDatafileKind0=PCBLib|IsCurrent=T|DatalinksLocked=T|DatabaseDatalinksLocked=T
|RECORD=46|OwnerIndex=380
|RECORD=48|OwnerIndex=380
|RECORD=41|OwnerIndex=382|IndexInSheet=-1|OwnerPartId=-1|Color=8388608|FontID=1|IsHidden=T|Text=2D|Name=Available Preview Images
|RECORD=45|OwnerIndex=379|IndexInSheet=-1|Description=Chip Resistor, 2-Leads, Body 1.00x0.50mm, IPC High Density|UseComponentLibrary=T|ModelName=RESC1005X40X25LL05T10|ModelType=PCBLIB|DatafileCount=1|ModelDatafileEntity0=RESC1005X40X25LL05T10|ModelDatafileKind0=PCBLib|DatalinksLocked=T|DatabaseDatalinksLocked=T
|RECORD=46|OwnerIndex=384
|RECORD=48|OwnerIndex=384
|RECORD=41|OwnerIndex=386|IndexInSheet=-1|OwnerPartId=-1|Color=8388608|FontID=1|IsHidden=T|Text=2D|Name=Available Preview Images
|RECORD=45|OwnerIndex=379|IndexInSheet=-1|Description=Chip Resistor, 2-Leads, Body 1.00x0.50mm, IPC Low Density|UseComponentLibrary=T|ModelName=RESC1005X40X25ML05T10|ModelType=PCBLIB|DatafileCount=1|ModelDatafileEntity0=RESC1005X40X25ML05T10|ModelDatafileKind0=PCBLib|DatalinksLocked=T|DatabaseDatalinksLocked=T
|RECORD=46|OwnerIndex=388
|RECORD=48|OwnerIndex=388
|RECORD=41|OwnerIndex=390|IndexInSheet=-1|OwnerPartId=-1|Color=8388608|FontID=1|IsHidden=T|Text=2D|Name=Available Preview Images
|RECORD=1|LibReference=RES|PartCount=2|DisplayModeCount=2|IndexInSheet=75|OwnerPartId=-1|Location.X=960|Location.Y=630|CurrentPartId=1|SourceLibraryName=Altium Content Vault|TargetFileName=*|AreaColor=11599871|Color=128|PartIDLocked=F|DesignItemId=CMP-2002-06457-1|AllPinCount=2
|RECORD=2|OwnerIndex=392|OwnerPartId=1|OwnerPartDisplayMode=1|FormalType=1|Electrical=4|PinConglomerate=32|PinLength=10|Location.X=980|Location.Y=620|Name=2|Designator=2|PinPropagationDelay=0.000000E+000
|RECORD=2|OwnerIndex=392|OwnerPartId=1|OwnerPartDisplayMode=1|FormalType=1|Electrical=4|PinConglomerate=34|PinLength=10|Location.X=960|Location.Y=620|Name=1|Designator=1|PinPropagationDelay=0.000000E+000
|RECORD=14|OwnerIndex=392|IsNotAccesible=T|IndexInSheet=2|OwnerPartId=1|OwnerPartDisplayMode=1|Location.X=960|Location.Y=616|Corner.X=980|Corner.Y=624|LineWidth=1|Color=16711680|AreaColor=11599871
|RECORD=2|OwnerIndex=392|OwnerPartId=1|FormalType=1|Electrical=4|PinConglomerate=32|PinLength=10|Location.X=980|Location.Y=620|Name=2|Designator=2|PinPropagationDelay=0.000000E+000
|RECORD=2|OwnerIndex=392|OwnerPartId=1|FormalType=1|Electrical=4|PinConglomerate=34|PinLength=10|Location.X=960|Location.Y=620|Name=1|Designator=1|PinPropagationDelay=0.000000E+000
|RECORD=6|OwnerIndex=392|IsNotAccesible=T|IndexInSheet=5|OwnerPartId=1|LineWidth=1|Color=16711680|LocationCount=10|X1=980|Y1=620|X2=976|Y2=620|X3=975|Y3=618|X4=973|Y4=622|X5=971|Y5=618|X6=969|Y6=622|X7=967|Y7=618|X8=965|Y8=622|X9=964|Y9=620|X10=960|Y10=620
|RECORD=41|OwnerIndex=392|IndexInSheet=6|OwnerPartId=-1|Location.X=948|Location.Y=633|Color=8388608|FontID=1|IsHidden=T|Text=Panasonic|Name=Manufacturer
|RECORD=41|OwnerIndex=392|IndexInSheet=7|OwnerPartId=-1|Location.X=948|Location.Y=633|Color=8388608|FontID=1|IsHidden=T|Text=ERJ-U020R00X|Name=Part Number
|RECORD=34|OwnerIndex=392|IndexInSheet=-1|OwnerPartId=-1|Location.X=940|Location.Y=620|Color=8388608|FontID=1|Text=R15|Name=Designator|ReadOnlyState=1
|RECORD=41|OwnerIndex=392|IndexInSheet=-1|OwnerPartId=-1|Location.X=980|Location.Y=620|Color=8388608|FontID=1|Text=0_5%_0402|Name=Comment
|RECORD=44|OwnerIndex=392
|RECORD=45|OwnerIndex=407|IndexInSheet=-1|Description=Chip Resistor, 2-Leads, Body 1.00x0.50mm, IPC Medium Density|UseComponentLibrary=T|ModelName=RESC1005X40X25NL05T10|ModelType=PCBLIB|DatafileCount=1|ModelDatafileEntity0=RESC1005X40X25NL05T10|ModelDatafileKind0=PCBLib|IsCurrent=T|DatalinksLocked=T|DatabaseDatalinksLocked=T
|RECORD=46|OwnerIndex=408
|RECORD=48|OwnerIndex=408
|RECORD=41|OwnerIndex=410|IndexInSheet=-1|OwnerPartId=-1|Color=8388608|FontID=1|IsHidden=T|Text=2D|Name=Available Preview Images
|RECORD=45|OwnerIndex=407|IndexInSheet=-1|Description=Chip Resistor, 2-Leads, Body 1.00x0.50mm, IPC High Density|UseComponentLibrary=T|ModelName=RESC1005X40X25LL05T10|ModelType=PCBLIB|DatafileCount=1|ModelDatafileEntity0=RESC1005X40X25LL05T10|ModelDatafileKind0=PCBLib|DatalinksLocked=T|DatabaseDatalinksLocked=T
|RECORD=46|OwnerIndex=412
|RECORD=48|OwnerIndex=412
|RECORD=41|OwnerIndex=414|IndexInSheet=-1|OwnerPartId=-1|Color=8388608|FontID=1|IsHidden=T|Text=2D|Name=Available Preview Images
|RECORD=45|OwnerIndex=407|IndexInSheet=-1|Description=Chip Resistor, 2-Leads, Body 1.00x0.50mm, IPC Low Density|UseComponentLibrary=T|ModelName=RESC1005X40X25ML05T10|ModelType=PCBLIB|DatafileCount=1|ModelDatafileEntity0=RESC1005X40X25ML05T10|ModelDatafileKind0=PCBLib|DatalinksLocked=T|DatabaseDatalinksLocked=T
|RECORD=46|OwnerIndex=416
|RECORD=48|OwnerIndex=416
|RECORD=41|OwnerIndex=418|IndexInSheet=-1|OwnerPartId=-1|Color=8388608|FontID=1|IsHidden=T|Text=2D|Name=Available Preview Images
|RECORD=17|IndexInSheet=76|OwnerPartId=-1|ShowNetName=T|Location.X=1050|Location.Y=620|Color=255|FontID=1|Text=TP1|IsCrossSheetConnector=T
|RECORD=27|IndexInSheet=77|OwnerPartId=-1|LineWidth=1|Color=8388608|LocationCount=4|X1=1050|Y1=620|X2=1030|Y2=620|X3=1030|Y3=630|X4=990|Y4=630
|RECORD=27|IndexInSheet=78|OwnerPartId=-1|LineWidth=1|Color=8388608|LocationCount=2|X1=1030|Y1=620|X2=990|Y2=620
|RECORD=27|IndexInSheet=79|OwnerPartId=-1|LineWidth=1|Color=8388608|LocationCount=2|X1=950|Y1=630|X2=890|Y2=630
|RECORD=27|IndexInSheet=80|OwnerPartId=-1|LineWidth=1|Color=8388608|LocationCount=2|X1=890|Y1=620|X2=950|Y2=620
|RECORD=29|IndexInSheet=-1|OwnerPartId=-1|Location.X=540|Location.Y=690|Color=128
|RECORD=29|IndexInSheet=-1|OwnerPartId=-1|Location.X=560|Location.Y=650|Color=128
|RECORD=29|IndexInSheet=-1|OwnerPartId=-1|Location.X=580|Location.Y=760|Color=128
|RECORD=29|IndexInSheet=-1|OwnerPartId=-1|Location.X=660|Location.Y=340|Color=128
|RECORD=29|IndexInSheet=-1|OwnerPartId=-1|Location.X=660|Location.Y=350|Color=128
|RECORD=29|IndexInSheet=-1|OwnerPartId=-1|Location.X=660|Location.Y=360|Color=128
|RECORD=29|IndexInSheet=-1|OwnerPartId=-1|Location.X=660|Location.Y=370|Color=128
|RECORD=29|IndexInSheet=-1|OwnerPartId=-1|Location.X=660|Location.Y=380|Color=128
|RECORD=29|IndexInSheet=-1|OwnerPartId=-1|Location.X=660|Location.Y=390|Color=128
|RECORD=29|IndexInSheet=-1|OwnerPartId=-1|Location.X=660|Location.Y=400|Color=128
|RECORD=29|IndexInSheet=-1|OwnerPartId=-1|Location.X=660|Location.Y=410|Color=128
|RECORD=29|IndexInSheet=-1|OwnerPartId=-1|Location.X=660|Location.Y=420|Color=128
|RECORD=29|IndexInSheet=-1|OwnerPartId=-1|Location.X=660|Location.Y=430|Color=128
|RECORD=29|IndexInSheet=-1|OwnerPartId=-1|Location.X=660|Location.Y=490|Color=128
|RECORD=29|IndexInSheet=-1|OwnerPartId=-1|Location.X=660|Location.Y=510|Color=128
|RECORD=29|IndexInSheet=-1|OwnerPartId=-1|Location.X=660|Location.Y=680|Color=128
|RECORD=29|IndexInSheet=-1|OwnerPartId=-1|Location.X=660|Location.Y=690|Color=128
|RECORD=29|IndexInSheet=-1|OwnerPartId=-1|Location.X=660|Location.Y=700|Color=128
|RECORD=29|IndexInSheet=-1|OwnerPartId=-1|Location.X=660|Location.Y=710|Color=128
|RECORD=29|IndexInSheet=-1|OwnerPartId=-1|Location.X=660|Location.Y=760|Color=128
|RECORD=29|IndexInSheet=-1|OwnerPartId=-1|Location.X=1030|Location.Y=620|Color=128